(kicad_pcb
	(version 20241229)
	(generator "pcbnew")
	(generator_version "9.0")
	(general
		(thickness 1.711)
		(legacy_teardrops no)
	)
	(paper "A4")
	(title_block
		(title "Antmicro Baseboard for Jetson AGX Thor")
		(date "2026-02-18")
		(rev "1.1.0")
		(company "Antmicro Ltd")
		(comment 1 "www.antmicro.com")
		(comment 9 "footprints 929-932 of 1170")
	)
	(layers
		(0 "F.Cu" signal)
		(4 "In1.Cu" signal)
		(6 "In2.Cu" signal)
		(8 "In3.Cu" signal)
		(10 "In4.Cu" jumper)
		(12 "In5.Cu" signal)
		(14 "In6.Cu" signal)
		(16 "In7.Cu" signal)
		(18 "In8.Cu" signal)
		(2 "B.Cu" signal)
		(9 "F.Adhes" user "F.Adhesive")
		(11 "B.Adhes" user "B.Adhesive")
		(13 "F.Paste" user)
		(15 "B.Paste" user)
		(5 "F.SilkS" user "F.Silkscreen")
		(7 "B.SilkS" user "B.Silkscreen")
		(1 "F.Mask" user)
		(3 "B.Mask" user)
		(17 "Dwgs.User" user "User.Drawings")
		(19 "Cmts.User" user "User.Comments")
		(21 "Eco1.User" user "User.Eco1")
		(23 "Eco2.User" user "User.Eco2")
		(25 "Edge.Cuts" user)
		(27 "Margin" user)
		(31 "F.CrtYd" user "F.Courtyard")
		(29 "B.CrtYd" user "B.Courtyard")
		(35 "F.Fab" user)
		(33 "B.Fab" user)
	)
	(footprint "antmicro-footprints:R_0603_1608Metric"
		(layer "B.Cu")
		(at 100.1 130.7 180)
		(descr "Resistor SMD 0603")
		(tags "resistor SMD 0603")
		(property "Reference" "R250"
			(at -4.1 -0.45 0)
			(layer "B.SilkS")
			(effects
				(font
					(size 0.7 0.7)
					(thickness 0.15)
				)
				(justify left bottom mirror)
			)
		)
		(property "Value" "R_0R_22.4A_0603"
			(at 0 -1.6 0)
			(layer "B.Fab")
			(effects
				(font
					(size 0.7 0.7)
					(thickness 0.15)
				)
				(justify left bottom mirror)
			)
		)
		(property "Datasheet" "https://fscdn.rohm.com/en/products/databook/datasheet/passive/resistor/chip_resistor/pmr-jpw-e.pdf"
			(at 0 0 0)
			(layer "B.Fab")
			(hide yes)
			(effects
				(font
					(size 1.27 1.27)
					(thickness 0.15)
				)
				(justify mirror)
			)
		)
		(property "Description" "SMD Chip Resistor"
			(at 0 0 0)
			(layer "B.Fab")
			(hide yes)
			(effects
				(font
					(size 1.27 1.27)
					(thickness 0.15)
				)
				(justify mirror)
			)
		)
		(property "MPN" "PMR03EZPJ000"
			(at 0 0 0)
			(unlocked yes)
			(layer "B.Fab")
			(hide yes)
			(effects
				(font
					(size 1 1)
					(thickness 0.15)
				)
				(justify mirror)
			)
		)
		(property "Manufacturer" "ROHM Semiconductor"
			(at 0 0 0)
			(unlocked yes)
			(layer "B.Fab")
			(hide yes)
			(effects
				(font
					(size 1 1)
					(thickness 0.15)
				)
				(justify mirror)
			)
		)
		(property "Val" "0R"
			(at 0 0 0)
			(unlocked yes)
			(layer "B.Fab")
			(hide yes)
			(effects
				(font
					(size 1 1)
					(thickness 0.15)
				)
				(justify mirror)
			)
		)
		(property "Max. Curr." "22.4A"
			(at 0 0 0)
			(unlocked yes)
			(layer "B.Fab")
			(hide yes)
			(effects
				(font
					(size 1 1)
					(thickness 0.15)
				)
				(justify mirror)
			)
		)
		(property "Author" "Antmicro"
			(at 0 0 0)
			(unlocked yes)
			(layer "B.Fab")
			(hide yes)
			(effects
				(font
					(size 1 1)
					(thickness 0.15)
				)
				(justify mirror)
			)
		)
		(property "License" "Apache-2.0"
			(at 0 0 0)
			(unlocked yes)
			(layer "B.Fab")
			(hide yes)
			(effects
				(font
					(size 1 1)
					(thickness 0.15)
				)
				(justify mirror)
			)
		)
		(property "Tolerance" "template_tolerance"
			(at 0 0 0)
			(unlocked yes)
			(layer "B.Fab")
			(hide yes)
			(effects
				(font
					(size 1 1)
					(thickness 0.15)
				)
				(justify mirror)
			)
		)
		(sheetname "/Expansion connector/")
		(sheetfile "expansion_connector.kicad_sch")
		(attr smd exclude_from_pos_files exclude_from_bom dnp)
		(fp_line
			(start -0.15 0.4)
			(end 0.15 0.4)
			(stroke
				(width 0.15)
				(type solid)
			)
			(layer "B.SilkS")
		)
		(fp_line
			(start -0.15 -0.4)
			(end 0.15 -0.4)
			(stroke
				(width 0.15)
				(type solid)
			)
			(layer "B.SilkS")
		)
		(fp_rect
			(start -1.25 0.65)
			(end 1.25 -0.65)
			(stroke
				(width 0.05)
				(type solid)
			)
			(fill no)
			(layer "B.CrtYd")
		)
		(fp_rect
			(start -0.8 0.4)
			(end 0.8 -0.4)
			(stroke
				(width 0.15)
				(type solid)
			)
			(fill no)
			(layer "B.Fab")
		)
		(fp_text user "${REFERENCE}"
			(at -1.25 -3.898 0)
			(layer "B.Fab")
			(effects
				(font
					(size 0.7 0.7)
					(thickness 0.15)
				)
				(justify left bottom mirror)
			)
		)
		(fp_text user "License: Apache-2.0"
			(at -1.25 -5.9 0)
			(layer "B.Fab")
			(effects
				(font
					(size 0.7 0.7)
					(thickness 0.15)
				)
				(justify left bottom mirror)
			)
		)
		(fp_text user "Author: Antmicro"
			(at -1.25 -4.9 0)
			(layer "B.Fab")
			(effects
				(font
					(size 0.7 0.7)
					(thickness 0.15)
				)
				(justify left bottom mirror)
			)
		)
		(pad "1" smd roundrect
			(at -0.7 0 180)
			(size 0.8 1)
			(layers "B.Cu" "B.Mask" "B.Paste")
			(roundrect_rratio 0.2)
			(net 5 "+5V")
			(pintype "passive")
		)
		(pad "2" smd roundrect
			(at 0.7 0 180)
			(size 0.8 1)
			(layers "B.Cu" "B.Mask" "B.Paste")
			(roundrect_rratio 0.2)
			(net 307 "/Expansion connector/+5V_FMC")
			(pintype "passive")
		)
	)
	(footprint "antmicro-footprints:R_0402_1005Metric"
		(layer "B.Cu")
		(at 124.6 132.9 180)
		(descr "Resistor SMD 0402")
		(tags "resistor SMD 0402")
		(property "Reference" "R214"
			(at -1.65 4.65 0)
			(layer "B.SilkS")
			(effects
				(font
					(size 0.7 0.7)
					(thickness 0.15)
				)
				(justify left bottom mirror)
			)
		)
		(property "Value" "R_0R_0402"
			(at -1.011843 -1.772046 0)
			(layer "B.Fab")
			(effects
				(font
					(size 0.7 0.7)
					(thickness 0.15)
				)
				(justify left bottom mirror)
			)
		)
		(property "Datasheet" "https://industrial.panasonic.com/cdbs/www-data/pdf/RDA0000/AOA0000C301.pdf"
			(at 0 0 0)
			(layer "B.Fab")
			(hide yes)
			(effects
				(font
					(size 1.27 1.27)
					(thickness 0.15)
				)
				(justify mirror)
			)
		)
		(property "Description" "SMD Chip Resistor, Jumper, 0 ohm, 100 mW, 0402 [1005 Metric], Thick Film, General Purpose"
			(at 0 0 0)
			(layer "B.Fab")
			(hide yes)
			(effects
				(font
					(size 1.27 1.27)
					(thickness 0.15)
				)
				(justify mirror)
			)
		)
		(property "MPN" "ERJ2GE0R00X"
			(at 0 0 0)
			(unlocked yes)
			(layer "B.Fab")
			(hide yes)
			(effects
				(font
					(size 1 1)
					(thickness 0.15)
				)
				(justify mirror)
			)
		)
		(property "Manufacturer" "Panasonic"
			(at 0 0 0)
			(unlocked yes)
			(layer "B.Fab")
			(hide yes)
			(effects
				(font
					(size 1 1)
					(thickness 0.15)
				)
				(justify mirror)
			)
		)
		(property "License" "Apache-2.0"
			(at 0 0 0)
			(unlocked yes)
			(layer "B.Fab")
			(hide yes)
			(effects
				(font
					(size 1 1)
					(thickness 0.15)
				)
				(justify mirror)
			)
		)
		(property "Author" "Antmicro"
			(at 0 0 0)
			(unlocked yes)
			(layer "B.Fab")
			(hide yes)
			(effects
				(font
					(size 1 1)
					(thickness 0.15)
				)
				(justify mirror)
			)
		)
		(property "Val" "0R"
			(at 0 0 0)
			(unlocked yes)
			(layer "B.Fab")
			(hide yes)
			(effects
				(font
					(size 1 1)
					(thickness 0.15)
				)
				(justify mirror)
			)
		)
		(property "Tolerance" "~"
			(at 0 0 0)
			(unlocked yes)
			(layer "B.Fab")
			(hide yes)
			(effects
				(font
					(size 1 1)
					(thickness 0.15)
				)
				(justify mirror)
			)
		)
		(property "Current" "1A"
			(at 0 0 0)
			(unlocked yes)
			(layer "B.Fab")
			(hide yes)
			(effects
				(font
					(size 1 1)
					(thickness 0.15)
				)
				(justify mirror)
			)
		)
		(sheetname "/M.2/")
		(sheetfile "m2.kicad_sch")
		(attr smd)
		(fp_poly
			(pts
				(xy -0.925 0.47) (xy 0.925 0.47) (xy 0.925 -0.47) (xy -0.925 -0.47)
			)
			(stroke
				(width 0.05)
				(type default)
			)
			(fill no)
			(layer "B.CrtYd")
		)
		(fp_poly
			(pts
				(xy -0.5 0.25) (xy 0.5 0.25) (xy 0.5 -0.25) (xy -0.5 -0.25)
			)
			(stroke
				(width 0.15)
				(type solid)
			)
			(fill no)
			(layer "B.Fab")
		)
		(fp_text user "Author: Antmicro"
			(at -0.95 -4.169 0)
			(layer "B.Fab")
			(effects
				(font
					(size 0.7 0.7)
					(thickness 0.15)
				)
				(justify left bottom mirror)
			)
		)
		(fp_text user "${REFERENCE}"
			(at -0.95 -3.168 0)
			(layer "B.Fab")
			(effects
				(font
					(size 0.7 0.7)
					(thickness 0.15)
				)
				(justify left bottom mirror)
			)
		)
		(fp_text user "License: Apache-2.0"
			(at -0.949999 -5.169 0)
			(layer "B.Fab")
			(effects
				(font
					(size 0.7 0.7)
					(thickness 0.15)
				)
				(justify left bottom mirror)
			)
		)
		(pad "1" smd roundrect
			(at -0.48 0 180)
			(size 0.59 0.64)
			(layers "B.Cu" "B.Mask" "B.Paste")
			(roundrect_rratio 0.25)
			(net 679 "/M.2/PCIe_{C1x1}.~{RST}")
			(pintype "passive")
		)
		(pad "2" smd roundrect
			(at 0.48 0 180)
			(size 0.59 0.64)
			(layers "B.Cu" "B.Mask" "B.Paste")
			(roundrect_rratio 0.25)
			(net 831 "/M.2/~{PERST_E}")
			(pintype "passive")
		)
	)
	(footprint "antmicro-footprints:C_0402_1005Metric"
		(layer "B.Cu")
		(at 110.25 106.5)
		(descr "Capacitor SMD 0402")
		(tags "capacitor SMD 0402")
		(property "Reference" "C185"
			(at -0.95 0.5 180)
			(layer "B.SilkS")
			(effects
				(font
					(size 0.7 0.7)
					(thickness 0.15)
				)
				(justify left bottom mirror)
			)
		)
		(property "Value" "C_220n_0402"
			(at -1.022927 -2.155213 180)
			(layer "B.Fab")
			(effects
				(font
					(size 0.7 0.7)
					(thickness 0.15)
				)
				(justify left bottom mirror)
			)
		)
		(property "Datasheet" "https://www.yageo.com/en/Chart/Download/pdf/CC0402KRX5R6BB224"
			(at 0 0 180)
			(layer "B.Fab")
			(hide yes)
			(effects
				(font
					(size 1.27 1.27)
					(thickness 0.15)
				)
				(justify mirror)
			)
		)
		(property "Description" "SMD Multilayer Ceramic Capacitor, 0.22 µF, 10 V, 0402 [1005 Metric], ± 10%, X5R, CC Series"
			(at 0 0 180)
			(layer "B.Fab")
			(hide yes)
			(effects
				(font
					(size 1.27 1.27)
					(thickness 0.15)
				)
				(justify mirror)
			)
		)
		(property "MPN" "CC0402KRX5R6BB224"
			(at 0 0 0)
			(unlocked yes)
			(layer "B.Fab")
			(hide yes)
			(effects
				(font
					(size 1 1)
					(thickness 0.15)
				)
				(justify mirror)
			)
		)
		(property "Val" "220n"
			(at 0 0 0)
			(unlocked yes)
			(layer "B.Fab")
			(hide yes)
			(effects
				(font
					(size 1 1)
					(thickness 0.15)
				)
				(justify mirror)
			)
		)
		(property "Voltage" "25V"
			(at 0 0 0)
			(unlocked yes)
			(layer "B.Fab")
			(hide yes)
			(effects
				(font
					(size 1 1)
					(thickness 0.15)
				)
				(justify mirror)
			)
		)
		(property "Dielectric" "X7R"
			(at 0 0 0)
			(unlocked yes)
			(layer "B.Fab")
			(hide yes)
			(effects
				(font
					(size 1 1)
					(thickness 0.15)
				)
				(justify mirror)
			)
		)
		(property "Manufacturer" "YAGEO"
			(at 0 0 0)
			(unlocked yes)
			(layer "B.Fab")
			(hide yes)
			(effects
				(font
					(size 1 1)
					(thickness 0.15)
				)
				(justify mirror)
			)
		)
		(property "License" "Apache-2.0"
			(at 0 0 0)
			(unlocked yes)
			(layer "B.Fab")
			(hide yes)
			(effects
				(font
					(size 1 1)
					(thickness 0.15)
				)
				(justify mirror)
			)
		)
		(property "Author" "Antmicro"
			(at 0 0 0)
			(unlocked yes)
			(layer "B.Fab")
			(hide yes)
			(effects
				(font
					(size 1 1)
					(thickness 0.15)
				)
				(justify mirror)
			)
		)
		(property "Public" "False"
			(at 0 0 0)
			(unlocked yes)
			(layer "B.Fab")
			(hide yes)
			(effects
				(font
					(size 1 1)
					(thickness 0.15)
				)
				(justify mirror)
			)
		)
		(sheetname "/M.2/")
		(sheetfile "m2.kicad_sch")
		(attr smd)
		(fp_rect
			(start -0.925 0.47)
			(end 0.925 -0.47)
			(stroke
				(width 0.05)
				(type default)
			)
			(fill no)
			(layer "B.CrtYd")
		)
		(fp_line
			(start -0.494 -0.248)
			(end -0.494 0.25)
			(stroke
				(width 0.15)
				(type solid)
			)
			(layer "B.Fab")
		)
		(fp_line
			(start -0.494 0.25)
			(end 0.504 0.25)
			(stroke
				(width 0.15)
				(type solid)
			)
			(layer "B.Fab")
		)
		(fp_line
			(start 0.504 -0.248)
			(end -0.494 -0.248)
			(stroke
				(width 0.15)
				(type solid)
			)
			(layer "B.Fab")
		)
		(fp_line
			(start 0.504 0.25)
			(end 0.504 -0.248)
			(stroke
				(width 0.15)
				(type solid)
			)
			(layer "B.Fab")
		)
		(fp_text user "License: Apache-2.0"
			(at -0.939 -5.799 180)
			(layer "B.Fab")
			(effects
				(font
					(size 0.7 0.7)
					(thickness 0.15)
				)
				(justify left bottom mirror)
			)
		)
		(fp_text user "Author: Antmicro"
			(at -0.939 -3.399 180)
			(layer "B.Fab")
			(effects
				(font
					(size 0.7 0.7)
					(thickness 0.15)
				)
				(justify left bottom mirror)
			)
		)
		(fp_text user "${REFERENCE}"
			(at -0.939 -4.599 180)
			(layer "B.Fab")
			(effects
				(font
					(size 0.7 0.7)
					(thickness 0.15)
				)
				(justify left bottom mirror)
			)
		)
		(pad "1" smd roundrect
			(at -0.48 0)
			(size 0.59 0.64)
			(layers "B.Cu" "B.Mask" "B.Paste")
			(roundrect_rratio 0.25)
			(net 411 "/M.2/PCIe_{C5x4}.TX0-")
			(pintype "passive")
		)
		(pad "2" smd roundrect
			(at 0.48 0)
			(size 0.59 0.64)
			(layers "B.Cu" "B.Mask" "B.Paste")
			(roundrect_rratio 0.25)
			(net 415 "/M.2/M2_M_PET0_N")
			(pintype "passive")
		)
	)
	(footprint "antmicro-footprints:R_0402_1005Metric"
		(layer "B.Cu")
		(at 136.8 65.2 -90)
		(descr "Resistor SMD 0402")
		(tags "resistor SMD 0402")
		(property "Reference" "R235"
			(at 0.9 -0.4 90)
			(layer "B.SilkS")
			(effects
				(font
					(size 0.7 0.7)
					(thickness 0.15)
				)
				(justify left bottom mirror)
			)
		)
		(property "Value" "R_10k_0402"
			(at -1.011843 -1.772046 90)
			(layer "B.Fab")
			(effects
				(font
					(size 0.7 0.7)
					(thickness 0.15)
				)
				(justify left bottom mirror)
			)
		)
		(property "Datasheet" "https://www.bourns.com/docs/product-datasheets/cr.pdf"
			(at 0 0 90)
			(layer "B.Fab")
			(hide yes)
			(effects
				(font
					(size 1.27 1.27)
					(thickness 0.15)
				)
				(justify mirror)
			)
		)
		(property "Description" "SMD Chip Resistor, 10 kohm, ± 1%, 62.5 mW, 0402 [1005 Metric], Thick Film, General Purpose"
			(at 0 0 90)
			(layer "B.Fab")
			(hide yes)
			(effects
				(font
					(size 1.27 1.27)
					(thickness 0.15)
				)
				(justify mirror)
			)
		)
		(property "Manufacturer" "Bourns"
			(at 0 0 90)
			(unlocked yes)
			(layer "B.Fab")
			(hide yes)
			(effects
				(font
					(size 1 1)
					(thickness 0.15)
				)
				(justify mirror)
			)
		)
		(property "MPN" "CR0402-FX-1002GLF"
			(at 0 0 90)
			(unlocked yes)
			(layer "B.Fab")
			(hide yes)
			(effects
				(font
					(size 1 1)
					(thickness 0.15)
				)
				(justify mirror)
			)
		)
		(property "Val" "10k"
			(at 0 0 90)
			(unlocked yes)
			(layer "B.Fab")
			(hide yes)
			(effects
				(font
					(size 1 1)
					(thickness 0.15)
				)
				(justify mirror)
			)
		)
		(property "License" "Apache-2.0"
			(at 0 0 90)
			(unlocked yes)
			(layer "B.Fab")
			(hide yes)
			(effects
				(font
					(size 1 1)
					(thickness 0.15)
				)
				(justify mirror)
			)
		)
		(property "Author" "Antmicro"
			(at 0 0 90)
			(unlocked yes)
			(layer "B.Fab")
			(hide yes)
			(effects
				(font
					(size 1 1)
					(thickness 0.15)
				)
				(justify mirror)
			)
		)
		(property "Tolerance" "1%"
			(at 0 0 90)
			(unlocked yes)
			(layer "B.Fab")
			(hide yes)
			(effects
				(font
					(size 1 1)
					(thickness 0.15)
				)
				(justify mirror)
			)
		)
		(sheetname "/Peripherals/")
		(sheetfile "peripherals.kicad_sch")
		(attr smd)
		(fp_poly
			(pts
				(xy -0.925 0.47) (xy 0.925 0.47) (xy 0.925 -0.47) (xy -0.925 -0.47)
			)
			(stroke
				(width 0.05)
				(type default)
			)
			(fill no)
			(layer "B.CrtYd")
		)
		(fp_poly
			(pts
				(xy -0.5 0.25) (xy 0.5 0.25) (xy 0.5 -0.25) (xy -0.5 -0.25)
			)
			(stroke
				(width 0.15)
				(type solid)
			)
			(fill no)
			(layer "B.Fab")
		)
		(fp_text user "${REFERENCE}"
			(at -0.95 -3.168 90)
			(layer "B.Fab")
			(effects
				(font
					(size 0.7 0.7)
					(thickness 0.15)
				)
				(justify left bottom mirror)
			)
		)
		(fp_text user "License: Apache-2.0"
			(at -0.949999 -5.169 90)
			(layer "B.Fab")
			(effects
				(font
					(size 0.7 0.7)
					(thickness 0.15)
				)
				(justify left bottom mirror)
			)
		)
		(fp_text user "Author: Antmicro"
			(at -0.95 -4.169 90)
			(layer "B.Fab")
			(effects
				(font
					(size 0.7 0.7)
					(thickness 0.15)
				)
				(justify left bottom mirror)
			)
		)
		(pad "1" smd roundrect
			(at -0.48 0 270)
			(size 0.59 0.64)
			(layers "B.Cu" "B.Mask" "B.Paste")
			(roundrect_rratio 0.25)
			(net 90 "/Peripherals/I2C_CONN_PEN")
			(pintype "passive")
		)
		(pad "2" smd roundrect
			(at 0.48 0 270)
			(size 0.59 0.64)
			(layers "B.Cu" "B.Mask" "B.Paste")
			(roundrect_rratio 0.25)
			(net 2 "+3V3")
			(pintype "passive")
		)
	)
)
